# T6G (Grand Teton) — schematic netlist excerpt (pin names and nets, part order shuffled) for the footprints in the layout excerpt that follows; sources: Cadence DE-HDL packaged netlist, KiCad conversion of 04192023_DAF0TMB3IC0_F0TG_MB_C_brd_V02_OCP.brd

R5013  Q_RES  1K 1% EMPTY  pkg 0402LF  page 159 : A = PVDD11_S3_P1 ; B = I3C_SPD_DDRGL_CPU1_LVC1_SDA
R3832  Q_RES  0 5% EMPTY  pkg 0402LF  page 140 : A = P3V3_OCP_PWRGD_2 ; B = OCP_V3_2_P3V3_PWRGD

(kicad_pcb
	(version 20260206)
	(generator "pcbnew")
	(generator_version "10.0")
	(general
		(thickness 1.6)
		(legacy_teardrops no)
	)
	(paper "A4")
	(title_block
		(title "04192023_DAF0TMB3IC0_F0TG_MB_C_brd_V02_OCP.brd")
		(comment 1 "Grand Teton / footprints 946-947 of 8354")
	)
	(layers
		(0 "F.Cu" signal "TOP")
		(4 "In1.Cu" signal "GND")
		(6 "In2.Cu" signal "IN1")
		(8 "In3.Cu" signal "GND1")
		(10 "In4.Cu" signal "IN2")
		(12 "In5.Cu" signal "GND2")
		(14 "In6.Cu" signal "IN3")
		(16 "In7.Cu" signal "GND3")
		(18 "In8.Cu" signal "VCC")
		(20 "In9.Cu" signal "VCC1")
		(22 "In10.Cu" signal "GND4")
		(24 "In11.Cu" signal "IN4")
		(26 "In12.Cu" signal "GND5")
		(28 "In13.Cu" signal "IN5")
		(30 "In14.Cu" signal "GND6")
		(32 "In15.Cu" signal "IN6")
		(34 "In16.Cu" signal "GND7")
		(2 "B.Cu" signal "BOTTOM")
		(9 "F.Adhes" user "F.Adhesive")
		(11 "B.Adhes" user "B.Adhesive")
		(13 "F.Paste" user "Package Geometry/Pastemask Top")
		(15 "B.Paste" user "Package Geometry/Pastemask Bottom")
		(5 "F.SilkS" user "Ref Des/Silkscreen Top")
		(7 "B.SilkS" user "Ref Des/Silkscreen Bottom")
		(1 "F.Mask" user "Board Geometry/Soldermask Top")
		(3 "B.Mask" user "Board Geometry/Soldermask Bottom")
		(17 "Dwgs.User" user "User.Drawings")
		(19 "Cmts.User" user "User.Comments")
		(21 "Eco1.User" user "User.Eco1")
		(23 "Eco2.User" user "User.Eco2")
		(25 "Edge.Cuts" user "Board Geometry/Outline")
		(27 "Margin" user)
		(31 "F.CrtYd" user "Package Geometry/Place Bound Top")
		(29 "B.CrtYd" user "Package Geometry/Place Bound Bottom")
		(35 "F.Fab" user "Ref Des/Assembly Top")
		(33 "B.Fab" user "Ref Des/Assembly Bottom")
	)
	(footprint ""
		(layer "F.Cu")
		(at 183.420766 -168.317418 -90)
		(property "Reference" "R5013"
			(at 0 0 270)
			(layer "F.SilkS")
			(hide yes)
			(effects
				(font
					(size 1.27 1.27)
				)
			)
		)
		(property "Value" ""
			(at 0 0 270)
			(layer "F.Fab")
			(effects
				(font
					(size 1.27 1.27)
				)
			)
		)
		(duplicate_pad_numbers_are_jumpers no)
		(fp_line
			(start -0.7874 0.4064)
			(end -0.7874 -0.4064)
			(stroke
				(width 0.1524)
				(type default)
			)
			(layer "F.SilkS")
		)
		(fp_line
			(start 0.7874 0.4064)
			(end -0.7874 0.4064)
			(stroke
				(width 0.1524)
				(type default)
			)
			(layer "F.SilkS")
		)
		(fp_line
			(start -0.7874 -0.4064)
			(end 0.7874 -0.4064)
			(stroke
				(width 0.1524)
				(type default)
			)
			(layer "F.SilkS")
		)
		(fp_line
			(start 0.7874 -0.4064)
			(end 0.7874 0.4064)
			(stroke
				(width 0.1524)
				(type default)
			)
			(layer "F.SilkS")
		)
		(fp_line
			(start -0.67945 0.3048)
			(end -0.67945 -0.305054)
			(stroke
				(width 0.1)
				(type default)
			)
			(layer "F.Fab")
		)
		(fp_line
			(start -0.12065 0.3048)
			(end -0.67945 0.3048)
			(stroke
				(width 0.1)
				(type default)
			)
			(layer "F.Fab")
		)
		(fp_line
			(start 0.120396 0.3048)
			(end 0.120396 0.2794)
			(stroke
				(width 0.1)
				(type default)
			)
			(layer "F.Fab")
		)
		(fp_line
			(start 0.67945 0.3048)
			(end 0.120396 0.3048)
			(stroke
				(width 0.1)
				(type default)
			)
			(layer "F.Fab")
		)
		(fp_line
			(start -0.12065 0.2794)
			(end -0.12065 0.3048)
			(stroke
				(width 0.1)
				(type default)
			)
			(layer "F.Fab")
		)
		(fp_line
			(start 0.120396 0.2794)
			(end -0.12065 0.2794)
			(stroke
				(width 0.1)
				(type default)
			)
			(layer "F.Fab")
		)
		(fp_line
			(start -0.12065 -0.2794)
			(end 0.12065 -0.2794)
			(stroke
				(width 0.1)
				(type default)
			)
			(layer "F.Fab")
		)
		(fp_line
			(start 0.12065 -0.2794)
			(end 0.12065 -0.3048)
			(stroke
				(width 0.1)
				(type default)
			)
			(layer "F.Fab")
		)
		(fp_line
			(start 0.12065 -0.3048)
			(end 0.67945 -0.3048)
			(stroke
				(width 0.1)
				(type default)
			)
			(layer "F.Fab")
		)
		(fp_line
			(start 0.67945 -0.3048)
			(end 0.67945 0.3048)
			(stroke
				(width 0.1)
				(type default)
			)
			(layer "F.Fab")
		)
		(fp_line
			(start -0.67945 -0.305054)
			(end -0.12065 -0.305054)
			(stroke
				(width 0.1)
				(type default)
			)
			(layer "F.Fab")
		)
		(fp_line
			(start -0.12065 -0.305054)
			(end -0.12065 -0.2794)
			(stroke
				(width 0.1)
				(type default)
			)
			(layer "F.Fab")
		)
		(pad "1" smd circle
			(at -0.40005 0 270)
			(size 0 0)
			(layers "F.Cu" "F.Mask" "F.Paste")
			(net "PVDD11_S3_P1")
		)
		(pad "2" smd circle
			(at 0.40005 0 270)
			(size 0 0)
			(layers "F.Cu" "F.Mask" "F.Paste")
			(net "I3C_SPD_DDRGL_CPU1_LVC1_SDA")
		)
	)
	(footprint ""
		(layer "F.Cu")
		(at 88.06053 -59.83097 -90)
		(property "Reference" "R3832"
			(at 0 0 270)
			(layer "F.SilkS")
			(hide yes)
			(effects
				(font
					(size 1.27 1.27)
				)
			)
		)
		(property "Value" ""
			(at 0 0 270)
			(layer "F.Fab")
			(effects
				(font
					(size 1.27 1.27)
				)
			)
		)
		(duplicate_pad_numbers_are_jumpers no)
		(fp_line
			(start -0.7874 0.4064)
			(end -0.7874 -0.4064)
			(stroke
				(width 0.1524)
				(type default)
			)
			(layer "F.SilkS")
		)
		(fp_line
			(start 0.7874 0.4064)
			(end -0.7874 0.4064)
			(stroke
				(width 0.1524)
				(type default)
			)
			(layer "F.SilkS")
		)
		(fp_line
			(start -0.7874 -0.4064)
			(end 0.7874 -0.4064)
			(stroke
				(width 0.1524)
				(type default)
			)
			(layer "F.SilkS")
		)
		(fp_line
			(start 0.7874 -0.4064)
			(end 0.7874 0.4064)
			(stroke
				(width 0.1524)
				(type default)
			)
			(layer "F.SilkS")
		)
		(fp_line
			(start -0.67945 0.3048)
			(end -0.67945 -0.305054)
			(stroke
				(width 0.1)
				(type default)
			)
			(layer "F.Fab")
		)
		(fp_line
			(start -0.12065 0.3048)
			(end -0.67945 0.3048)
			(stroke
				(width 0.1)
				(type default)
			)
			(layer "F.Fab")
		)
		(fp_line
			(start 0.120396 0.3048)
			(end 0.120396 0.2794)
			(stroke
				(width 0.1)
				(type default)
			)
			(layer "F.Fab")
		)
		(fp_line
			(start 0.67945 0.3048)
			(end 0.120396 0.3048)
			(stroke
				(width 0.1)
				(type default)
			)
			(layer "F.Fab")
		)
		(fp_line
			(start -0.12065 0.2794)
			(end -0.12065 0.3048)
			(stroke
				(width 0.1)
				(type default)
			)
			(layer "F.Fab")
		)
		(fp_line
			(start 0.120396 0.2794)
			(end -0.12065 0.2794)
			(stroke
				(width 0.1)
				(type default)
			)
			(layer "F.Fab")
		)
		(fp_line
			(start -0.12065 -0.2794)
			(end 0.12065 -0.2794)
			(stroke
				(width 0.1)
				(type default)
			)
			(layer "F.Fab")
		)
		(fp_line
			(start 0.12065 -0.2794)
			(end 0.12065 -0.3048)
			(stroke
				(width 0.1)
				(type default)
			)
			(layer "F.Fab")
		)
		(fp_line
			(start 0.12065 -0.3048)
			(end 0.67945 -0.3048)
			(stroke
				(width 0.1)
				(type default)
			)
			(layer "F.Fab")
		)
		(fp_line
			(start 0.67945 -0.3048)
			(end 0.67945 0.3048)
			(stroke
				(width 0.1)
				(type default)
			)
			(layer "F.Fab")
		)
		(fp_line
			(start -0.67945 -0.305054)
			(end -0.12065 -0.305054)
			(stroke
				(width 0.1)
				(type default)
			)
			(layer "F.Fab")
		)
		(fp_line
			(start -0.12065 -0.305054)
			(end -0.12065 -0.2794)
			(stroke
				(width 0.1)
				(type default)
			)
			(layer "F.Fab")
		)
		(pad "1" smd circle
			(at -0.40005 0 270)
			(size 0 0)
			(layers "F.Cu" "F.Mask" "F.Paste")
			(net "P3V3_OCP_PWRGD_2")
		)
		(pad "2" smd circle
			(at 0.40005 0 270)
			(size 0 0)
			(layers "F.Cu" "F.Mask" "F.Paste")
			(net "OCP_V3_2_P3V3_PWRGD")
		)
	)
)
